FILE_TYPE = CONNECTIVITY;
{Allegro Design Entry HDL 17.2-2016 S081 (4005846) 1/11/2022}
"PAGE_NUMBER" = 124;
0"NC";
1"PVCCD_HV_CPU0\g";
2"PVCCD_HV_CPU0\g";
3"PVNN_TERM_CPU0\g";
4"PVCCD_HV_CPU0\g";
5"PVCCD_HV_CPU0\g";
6"PVNN_TERM_CPU0\g";
7"PWRGD_DRAMPWRGD_CPU0_GH_LVC1_R";
8"PWRGD_DRAMPWRGD_CPU0_CD_LVC1_R";
9"PWRGD_DRAMPWRGD_CPU0_EF_LVC1_R";
10"PWRGD_DRAMPWRGD_CPU0_AB_LVC1_R2";
11"PWRGD_DRAMPWRGD_CPU0_GH_LVC1_R2";
12"PWRGD_DRAMPWRGD_CPU0_AB_LVC1_R";
13"PWRGD_DRAMPWRGD_CPU0_CD_LVC1_R2";
14"PWRGD_DRAMPWRGD_CPU0_EF_LVC1_R2";
15"PWRGD_CPU0_BUF_R";
16"RST_CPU0_BUF_R_N";
17"RST_CPU0_LVC1_N";
18"PWRGD_CPU0_LVC1";
19"PWRGD_DRAMPWRGD_CPU0_AB_R_LVC1";
20"PWRGD_DRAMPWRGD_CPU0_EF_R_LVC1";
21"RST_CPU0_LVC1_R_N";
22"PWRGD_CPU0_LVC1_R";
23"PWRGD_DRAMPWRGD_CPU0_CD_R_LVC1";
24"PWRGD_DRAMPWRGD_CPU0_GH_R_LVC1";
%"Q_RES"
"1","(-550,2800)","0","pure_quanta","I17";
;
PART_NUMBER"CS00002JB13"
PACK_TYPE"0402LF"
VALUE"0"
MATERIAL"CHIP"
WATTAGE"1/16W"
TOLERANCE"5%"
$LOCATION"R160"
CDS_LIB"pure_quanta"
CDS_LOCATION"R160"
$SEC"1"
CDS_SEC"1";
"B"
$PN"2"10;
"A"
$PN"1"19;
%"Q_RES"
"1","(-550,1975)","0","pure_quanta","I19";
;
PART_NUMBER"CS00002JB13"
VALUE"0"
TOLERANCE"5%"
PACK_TYPE"0402LF"
WATTAGE"1/16W"
MATERIAL"CHIP"
$LOCATION"R162"
CDS_LIB"pure_quanta"
CDS_LOCATION"R162"
$SEC"1"
CDS_SEC"1";
"B"
$PN"2"13;
"A"
$PN"1"23;
%"Q_RES"
"1","(-550,1125)","0","pure_quanta","I26";
;
PART_NUMBER"CS00002JB13"
WATTAGE"1/16W"
MATERIAL"CHIP"
TOLERANCE"5%"
PACK_TYPE"0402LF"
VALUE"0"
$LOCATION"R164"
CDS_LIB"pure_quanta"
CDS_LOCATION"R164"
$SEC"1"
CDS_SEC"1";
"B"
$PN"2"14;
"A"
$PN"1"20;
%"Q_RES"
"1","(-550,300)","0","pure_quanta","I33";
;
PART_NUMBER"CS00002JB13"
TOLERANCE"5%"
WATTAGE"1/16W"
VALUE"0"
MATERIAL"CHIP"
PACK_TYPE"0402LF"
$LOCATION"R166"
CDS_LIB"pure_quanta"
CDS_LOCATION"R166"
$SEC"1"
CDS_SEC"1";
"B"
$PN"2"11;
"A"
$PN"1"24;
%"Q_RES"
"1","(-550,-525)","0","pure_quanta","I43";
;
PART_NUMBER"CS00002JB13"
WATTAGE"1/16W"
MATERIAL"CHIP"
TOLERANCE"5%"
VALUE"0"
PACK_TYPE"0402LF"
$LOCATION"R168"
CDS_LIB"pure_quanta"
CDS_LOCATION"R168"
$SEC"1"
CDS_SEC"1";
"B"
$PN"2"15;
"A"
$PN"1"22;
%"UNIVERSAL_POWER"
"1","(4300,-250)","0","logical_power","I51";
;
HDL_POWER"PVNN_TERM_CPU0"
CDS_LIB"logical_power";
"A"3;
%"Q_RES"
"1","(-550,-1375)","0","pure_quanta","I52";
;
PART_NUMBER"CS00002JB13"
MATERIAL"CHIP"
WATTAGE"1/16W"
PACK_TYPE"0402LF"
TOLERANCE"5%"
VALUE"0"
$LOCATION"R171"
CDS_LIB"pure_quanta"
CDS_LOCATION"R171"
$SEC"1"
CDS_SEC"1";
"B"
$PN"2"16;
"A"
$PN"1"21;
%"UNIVERSAL_POWER"
"1","(4300,-1100)","0","logical_power","I59";
;
HDL_POWER"PVNN_TERM_CPU0"
CDS_LIB"logical_power";
"A"6;
%"Q_RES"
"1","(3700,-1200)","0","pure_quanta","I60";
;
PART_NUMBER"CS11002FB07"
TOLERANCE"1%"
WATTAGE"1/16W"
VALUE"100"
MATERIAL"CHIP"
PACK_TYPE"0402LF"
$LOCATION"R185"
CDS_LIB"pure_quanta"
CDS_LOCATION"R185"
$SEC"1"
CDS_SEC"1";
"B"
$PN"2"6;
"A"
$PN"1"16;
%"Q_RES"
"1","(3700,-350)","0","pure_quanta","I62";
;
PART_NUMBER"CS11002FB07"
VALUE"100"
WATTAGE"1/16W"
PACK_TYPE"0402LF"
TOLERANCE"1%"
MATERIAL"CHIP"
$LOCATION"R183"
CDS_LIB"pure_quanta"
CDS_LOCATION"R183"
$SEC"1"
CDS_SEC"1";
"B"
$PN"2"3;
"A"
$PN"1"15;
%"Q_RES"
"1","(3725,475)","0","pure_quanta","I68";
;
PART_NUMBER"CS11002FB07"
PACK_TYPE"0402LF"
TOLERANCE"1%"
MATERIAL"CHIP"
WATTAGE"1/16W"
VALUE"100"
$LOCATION"R181"
CDS_LIB"pure_quanta"
CDS_LOCATION"R181"
$SEC"1"
CDS_SEC"1";
"B"
$PN"2"1;
"A"
$PN"1"11;
%"UNIVERSAL_POWER"
"1","(4325,575)","0","logical_power","I69";
;
HDL_POWER"PVCCD_HV_CPU0"
CDS_LIB"logical_power";
"A"1;
%"Q_RES"
"1","(3725,1300)","0","pure_quanta","I70";
;
PART_NUMBER"CS11002FB07"
WATTAGE"1/16W"
VALUE"100"
PACK_TYPE"0402LF"
TOLERANCE"1%"
MATERIAL"CHIP"
$LOCATION"R179"
CDS_LIB"pure_quanta"
CDS_LOCATION"R179"
$SEC"1"
CDS_SEC"1";
"B"
$PN"2"2;
"A"
$PN"1"14;
%"UNIVERSAL_POWER"
"1","(4325,1400)","0","logical_power","I71";
;
HDL_POWER"PVCCD_HV_CPU0"
CDS_LIB"logical_power";
"A"2;
%"Q_RES"
"1","(3725,2150)","0","pure_quanta","I72";
;
PART_NUMBER"CS11002FB07"
TOLERANCE"1%"
PACK_TYPE"0402LF"
WATTAGE"1/16W"
VALUE"100"
MATERIAL"CHIP"
$LOCATION"R177"
CDS_LIB"pure_quanta"
CDS_LOCATION"R177"
$SEC"1"
CDS_SEC"1";
"B"
$PN"2"4;
"A"
$PN"1"13;
%"UNIVERSAL_POWER"
"1","(4325,2250)","0","logical_power","I73";
;
HDL_POWER"PVCCD_HV_CPU0"
CDS_LIB"logical_power";
"A"4;
%"UNIVERSAL_POWER"
"1","(4325,3075)","0","logical_power","I75";
;
HDL_POWER"PVCCD_HV_CPU0"
CDS_LIB"logical_power";
"A"5;
%"Q_RES"
"1","(3725,2975)","0","pure_quanta","I76";
;
PART_NUMBER"CS11002FB07"
TOLERANCE"1%"
MATERIAL"CHIP"
WATTAGE"1/16W"
VALUE"100"
PACK_TYPE"0402LF"
LOCATION"R175"
CDS_LIB"pure_quanta"
$SEC"1"
CDS_SEC"1";
"B"
$PN"2"5;
"A"
$PN"1"10;
%"Q_RES"
"1","(3700,-525)","0","pure_quanta","I77";
;
PART_NUMBER"CS11002FB07"
MATERIAL"CHIP"
VALUE"100"
TOLERANCE"1%"
PACK_TYPE"0402LF"
WATTAGE"1/16W"
LOCATION"R184"
CDS_LIB"pure_quanta"
$SEC"1"
CDS_SEC"1";
"B"
$PN"2"18;
"A"
$PN"1"15;
%"Q_RES"
"1","(3700,-1375)","0","pure_quanta","I78";
;
PART_NUMBER"CS11002FB07"
VALUE"100"
TOLERANCE"1%"
WATTAGE"1/16W"
PACK_TYPE"0402LF"
MATERIAL"CHIP"
LOCATION"R186"
CDS_LIB"pure_quanta"
$SEC"1"
CDS_SEC"1";
"B"
$PN"2"17;
"A"
$PN"1"16;
%"Q_RES"
"1","(3725,300)","0","pure_quanta","I79";
;
PART_NUMBER"CS11002FB07"
PACK_TYPE"0402LF"
TOLERANCE"1%"
WATTAGE"1/16W"
VALUE"100"
MATERIAL"CHIP"
$LOCATION"R4298"
CDS_LIB"pure_quanta"
CDS_LOCATION"R4298"
$SEC"1"
CDS_SEC"1";
"B"
$PN"2"7;
"A"
$PN"1"11;
%"Q_RES"
"1","(3725,1125)","0","pure_quanta","I82";
;
PART_NUMBER"CS11002FB07"
PACK_TYPE"0402LF"
WATTAGE"1/16W"
VALUE"100"
TOLERANCE"1%"
MATERIAL"CHIP"
$LOCATION"R4297"
CDS_LIB"pure_quanta"
CDS_LOCATION"R4297"
$SEC"1"
CDS_SEC"1";
"B"
$PN"2"9;
"A"
$PN"1"14;
%"Q_RES"
"1","(3725,1975)","0","pure_quanta","I85";
;
PART_NUMBER"CS11002FB07"
PACK_TYPE"0402LF"
MATERIAL"CHIP"
TOLERANCE"1%"
VALUE"100"
WATTAGE"1/16W"
$LOCATION"R4296"
CDS_LIB"pure_quanta"
CDS_LOCATION"R4296"
$SEC"1"
CDS_SEC"1";
"B"
$PN"2"8;
"A"
$PN"1"13;
%"Q_RES"
"1","(3725,2800)","0","pure_quanta","I87";
;
PART_NUMBER"CS11002FB07"
PACK_TYPE"0402LF"
MATERIAL"CHIP"
TOLERANCE"1%"
VALUE"100"
WATTAGE"1/16W"
$LOCATION"R4295"
CDS_LIB"pure_quanta"
CDS_LOCATION"R4295"
$SEC"1"
CDS_SEC"1";
"B"
$PN"2"12;
"A"
$PN"1"10;
END.
